# S9S_MB_2U (Grand Teton) — schematic netlist excerpt (pin names and nets, part order shuffled) for the footprints in the layout excerpt that follows; sources: Cadence DE-HDL packaged netlist, KiCad conversion of 03242023_DA0F0TMBIJ0_F0T_Motherboard_J_brd_V01_OCP.brd

C25  Q_CAP  10UF 16V 10% X6S  pkg C0805  page 89 : A = P12V_S3_AUX_CPU0_NVDIMM ; B = GND
R556  Q_RES  49.9 1% CHIP  pkg 0402LF  page 14 : A = SVID_ALERT1_CPU0_R_N ; B = PVNN_TERM_CPU0
C1917  Q_CAP  0.01UF 50V 10% X7R  pkg C0402  page 217 : A = P3V3_AUX_FPGA_VCCIO0 ; B = GND

(kicad_pcb
	(version 20260206)
	(generator "pcbnew")
	(generator_version "10.0")
	(general
		(thickness 1.6)
		(legacy_teardrops no)
	)
	(paper "A4")
	(title_block
		(title "03242023_DA0F0TMBIJ0_F0T_Motherboard_J_brd_V01_OCP.brd")
		(comment 1 "Grand Teton / footprints 5073-5075 of 6105")
	)
	(layers
		(0 "F.Cu" signal "TOP")
		(4 "In1.Cu" signal "GND")
		(6 "In2.Cu" signal "IN1")
		(8 "In3.Cu" signal "GND1")
		(10 "In4.Cu" signal "IN2")
		(12 "In5.Cu" signal "GND2")
		(14 "In6.Cu" signal "IN3")
		(16 "In7.Cu" signal "GND3")
		(18 "In8.Cu" signal "VCC")
		(20 "In9.Cu" signal "VCC1")
		(22 "In10.Cu" signal "GND4")
		(24 "In11.Cu" signal "IN4")
		(26 "In12.Cu" signal "GND5")
		(28 "In13.Cu" signal "IN5")
		(30 "In14.Cu" signal "GND6")
		(32 "In15.Cu" signal "IN6")
		(34 "In16.Cu" signal "GND7")
		(2 "B.Cu" signal "BOTTOM")
		(9 "F.Adhes" user "F.Adhesive")
		(11 "B.Adhes" user "B.Adhesive")
		(13 "F.Paste" user "Package Geometry/Pastemask Top")
		(15 "B.Paste" user "Package Geometry/Pastemask Bottom")
		(5 "F.SilkS" user "Ref Des/Silkscreen Top")
		(7 "B.SilkS" user "Ref Des/Silkscreen Bottom")
		(1 "F.Mask" user "Board Geometry/Soldermask Top")
		(3 "B.Mask" user "Board Geometry/Soldermask Bottom")
		(17 "Dwgs.User" user "User.Drawings")
		(19 "Cmts.User" user "User.Comments")
		(21 "Eco1.User" user "User.Eco1")
		(23 "Eco2.User" user "User.Eco2")
		(25 "Edge.Cuts" user "Board Geometry/Outline")
		(27 "Margin" user)
		(31 "F.CrtYd" user "Package Geometry/Place Bound Top")
		(29 "B.CrtYd" user "Package Geometry/Place Bound Bottom")
		(35 "F.Fab" user "Ref Des/Assembly Top")
		(33 "B.Fab" user "Ref Des/Assembly Bottom")
	)
	(footprint ""
		(layer "B.Cu")
		(at 307.984398 -190.45047 90)
		(property "Reference" "R556"
			(at 0 0 90)
			(layer "B.SilkS")
			(hide yes)
			(effects
				(font
					(size 1.27 1.27)
				)
				(justify mirror)
			)
		)
		(property "Value" ""
			(at 0 0 90)
			(layer "B.Fab")
			(effects
				(font
					(size 1.27 1.27)
				)
				(justify mirror)
			)
		)
		(duplicate_pad_numbers_are_jumpers no)
		(fp_line
			(start 0.7874 -0.4064)
			(end -0.7874 -0.4064)
			(stroke
				(width 0.1524)
				(type default)
			)
			(layer "B.SilkS")
		)
		(fp_line
			(start -0.7874 -0.4064)
			(end -0.7874 0.4064)
			(stroke
				(width 0.1524)
				(type default)
			)
			(layer "B.SilkS")
		)
		(fp_line
			(start 0.7874 0.4064)
			(end 0.7874 -0.4064)
			(stroke
				(width 0.1524)
				(type default)
			)
			(layer "B.SilkS")
		)
		(fp_line
			(start -0.7874 0.4064)
			(end 0.7874 0.4064)
			(stroke
				(width 0.1524)
				(type default)
			)
			(layer "B.SilkS")
		)
		(fp_line
			(start 0.67945 -0.305054)
			(end 0.12065 -0.305054)
			(stroke
				(width 0.1)
				(type default)
			)
			(layer "B.Fab")
		)
		(fp_line
			(start 0.12065 -0.305054)
			(end 0.12065 -0.2794)
			(stroke
				(width 0.1)
				(type default)
			)
			(layer "B.Fab")
		)
		(fp_line
			(start -0.12065 -0.3048)
			(end -0.67945 -0.3048)
			(stroke
				(width 0.1)
				(type default)
			)
			(layer "B.Fab")
		)
		(fp_line
			(start -0.67945 -0.3048)
			(end -0.67945 0.3048)
			(stroke
				(width 0.1)
				(type default)
			)
			(layer "B.Fab")
		)
		(fp_line
			(start 0.12065 -0.2794)
			(end -0.12065 -0.2794)
			(stroke
				(width 0.1)
				(type default)
			)
			(layer "B.Fab")
		)
		(fp_line
			(start -0.12065 -0.2794)
			(end -0.12065 -0.3048)
			(stroke
				(width 0.1)
				(type default)
			)
			(layer "B.Fab")
		)
		(fp_line
			(start 0.12065 0.2794)
			(end 0.12065 0.3048)
			(stroke
				(width 0.1)
				(type default)
			)
			(layer "B.Fab")
		)
		(fp_line
			(start -0.120396 0.2794)
			(end 0.12065 0.2794)
			(stroke
				(width 0.1)
				(type default)
			)
			(layer "B.Fab")
		)
		(fp_line
			(start 0.67945 0.3048)
			(end 0.67945 -0.305054)
			(stroke
				(width 0.1)
				(type default)
			)
			(layer "B.Fab")
		)
		(fp_line
			(start 0.12065 0.3048)
			(end 0.67945 0.3048)
			(stroke
				(width 0.1)
				(type default)
			)
			(layer "B.Fab")
		)
		(fp_line
			(start -0.120396 0.3048)
			(end -0.120396 0.2794)
			(stroke
				(width 0.1)
				(type default)
			)
			(layer "B.Fab")
		)
		(fp_line
			(start -0.67945 0.3048)
			(end -0.120396 0.3048)
			(stroke
				(width 0.1)
				(type default)
			)
			(layer "B.Fab")
		)
		(pad "1" smd circle
			(at 0.40005 0 270)
			(size 0 0)
			(layers "B.Cu" "B.Mask" "B.Paste")
			(net "SVID_ALERT1_CPU0_R_N")
		)
		(pad "2" smd circle
			(at -0.40005 0 270)
			(size 0 0)
			(layers "B.Cu" "B.Mask" "B.Paste")
			(net "PVNN_TERM_CPU0")
		)
	)
	(footprint ""
		(layer "B.Cu")
		(at 175.355758 -112.97539 180)
		(property "Reference" "C1917"
			(at 0 0 0)
			(layer "B.SilkS")
			(hide yes)
			(effects
				(font
					(size 1.27 1.27)
				)
				(justify mirror)
			)
		)
		(property "Value" ""
			(at 0 0 0)
			(layer "B.Fab")
			(effects
				(font
					(size 1.27 1.27)
				)
				(justify mirror)
			)
		)
		(duplicate_pad_numbers_are_jumpers no)
		(fp_line
			(start 0.69215 0.2921)
			(end 0.69215 -0.2921)
			(stroke
				(width 0.1524)
				(type default)
			)
			(layer "B.SilkS")
		)
		(fp_line
			(start 0.69215 -0.2921)
			(end -0.69215 -0.2921)
			(stroke
				(width 0.1524)
				(type default)
			)
			(layer "B.SilkS")
		)
		(fp_line
			(start -0.69215 0.2921)
			(end 0.69215 0.2921)
			(stroke
				(width 0.1524)
				(type default)
			)
			(layer "B.SilkS")
		)
		(fp_line
			(start -0.69215 -0.2921)
			(end -0.69215 0.2921)
			(stroke
				(width 0.1524)
				(type default)
			)
			(layer "B.SilkS")
		)
		(fp_line
			(start 0.51435 0.2794)
			(end 0.51435 -0.2794)
			(stroke
				(width 0.1)
				(type default)
			)
			(layer "B.Fab")
		)
		(fp_line
			(start 0.51435 -0.2794)
			(end -0.51435 -0.2794)
			(stroke
				(width 0.1)
				(type default)
			)
			(layer "B.Fab")
		)
		(fp_line
			(start -0.51435 0.2794)
			(end 0.51435 0.2794)
			(stroke
				(width 0.1)
				(type default)
			)
			(layer "B.Fab")
		)
		(fp_line
			(start -0.51435 -0.2794)
			(end -0.51435 0.2794)
			(stroke
				(width 0.1)
				(type default)
			)
			(layer "B.Fab")
		)
		(pad "1" smd circle
			(at 0.40005 0)
			(size 0 0)
			(layers "B.Cu" "B.Mask" "B.Paste")
			(net "P3V3_AUX_FPGA_VCCIO0")
		)
		(pad "2" smd circle
			(at -0.40005 0)
			(size 0 0)
			(layers "B.Cu" "B.Mask" "B.Paste")
			(net "GND")
		)
		(zone
			(layer "B.Cu")
			(hatch none 0.5)
			(connect_pads
				(clearance 0)
			)
			(min_thickness 0.25)
			(keepout
				(tracks not_allowed)
				(vias allowed)
				(pads allowed)
				(copperpour not_allowed)
				(footprints allowed)
			)
			(placement
				(enabled no)
				(sheetname "")
			)
			(fill
				(thermal_gap 0.5)
				(thermal_bridge_width 0.5)
				(island_removal_mode 0)
			)
			(polygon
				(pts
					(xy 175.165258 -113.06302) (xy 175.256698 -113.121186) (xy 175.456088 -113.121186) (xy 175.546258 -113.06302)
					(xy 175.546258 -112.88776) (xy 175.456088 -112.82934) (xy 175.256698 -112.82934) (xy 175.165258 -112.887506)
				)
			)
		)
	)
	(footprint ""
		(layer "B.Cu")
		(at 263.637014 -321.549776 -90)
		(property "Reference" "C25"
			(at 0 0 90)
			(layer "B.SilkS")
			(hide yes)
			(effects
				(font
					(size 1.27 1.27)
				)
				(justify mirror)
			)
		)
		(property "Value" ""
			(at 0 0 90)
			(layer "B.Fab")
			(effects
				(font
					(size 1.27 1.27)
				)
				(justify mirror)
			)
		)
		(duplicate_pad_numbers_are_jumpers no)
		(fp_line
			(start -1.524 0.762)
			(end 1.524 0.762)
			(stroke
				(width 0.1524)
				(type default)
			)
			(layer "B.SilkS")
		)
		(fp_line
			(start 1.524 0.762)
			(end 1.524 -0.762)
			(stroke
				(width 0.1524)
				(type default)
			)
			(layer "B.SilkS")
		)
		(fp_line
			(start -1.524 -0.762)
			(end -1.524 0.762)
			(stroke
				(width 0.1524)
				(type default)
			)
			(layer "B.SilkS")
		)
		(fp_line
			(start 1.524 -0.762)
			(end -1.524 -0.762)
			(stroke
				(width 0.1524)
				(type default)
			)
			(layer "B.SilkS")
		)
		(fp_line
			(start -1.1049 0.724916)
			(end -1.1049 -0.724916)
			(stroke
				(width 0.1)
				(type default)
			)
			(layer "B.Fab")
		)
		(fp_line
			(start 1.1049 0.724916)
			(end -1.1049 0.724916)
			(stroke
				(width 0.1)
				(type default)
			)
			(layer "B.Fab")
		)
		(fp_line
			(start -1.1049 -0.724916)
			(end 1.1049 -0.724916)
			(stroke
				(width 0.1)
				(type default)
			)
			(layer "B.Fab")
		)
		(fp_line
			(start 1.1049 -0.724916)
			(end 1.1049 0.724916)
			(stroke
				(width 0.1)
				(type default)
			)
			(layer "B.Fab")
		)
		(pad "1" smd rect
			(at 0.889 0 270)
			(size 1.016 1.27)
			(layers "B.Cu" "B.Mask" "B.Paste")
			(net "P12V_S3_AUX_CPU0_NVDIMM")
		)
		(pad "2" smd rect
			(at -0.889 0 270)
			(size 1.016 1.27)
			(layers "B.Cu" "B.Mask" "B.Paste")
			(net "GND")
		)
	)
)
